FILE_TYPE = CONNECTIVITY;
{Allegro Design Entry HDL 17.4-2019 S026 (4007227) 1/17/2022}
"PAGE_NUMBER" = 100;
0"NC";
1"GND\g";
2"GND\g";
3"P3V3\g";
4"M_D_CPU1_SA_CB<7:0>";
5"M_D_CPU1_SB_CB<7:0>";
6"M_D_CPU1_SA_CA<6:0>";
7"M_D_CPU1_SB_CA<6:0>";
8"M_D_CPU1_SA_DQ<31:0>";
9"M_D_CPU1_SB_DQ<31:0>";
10"M_D_CPU1_SA_DQS_DN<9:0>";
11"M_D_CPU1_SA_DQS_DP<9:0>";
12"M_D_CPU1_SB_DQS_DP<9:0>";
13"M_D_CPU1_SB_DQS_DN<9:0>";
14"M_D_CPU1_SB_CB<0>";
15"PD_CHD_CPU1_DIMM_SAA";
16"P3V3_AUX\g";
17"I3C_SPD_DDRAF_CPU1_SDA";
18"I3C_SPD_DDRD_CPU1_SDA";
19"I3C_SPD_DDRAF_CPU1_SCL";
20"M_D_CPU1_ALERT_N";
21"M_D_CPU1_RESET_N";
22"I3C_SPD_DDRD_CPU1_SCL";
23"M_D_CPU1_SB_CB<1>";
24"M_D_CPU1_SB_DQ<16>";
25"M_D_CPU1_SB_DQ<17>";
26"PWRGD_CHD_CPU1_DIMM";
27"PWRGD_CHAF_CPU1";
28"M_D_CPU1_SA_RSP<0>";
29"M_D_CPU1_SB_RSP<0>";
30"P12V_MEM_CPU1\g";
31"GND\g";
32"GND\g";
33"GND\g";
34"M_D_CPU1_SB_DQS_DP<9>";
35"M_D_CPU1_SB_DQS_DN<9>";
36"M_D_CPU1_SA_DQS_DP<9>";
37"M_D_CPU1_SA_DQS_DN<9>";
38"M_D_CPU1_SA_DQS_DP<8>";
39"M_D_CPU1_SA_DQS_DN<8>";
40"M_D_CPU1_SB_DQS_DN<7>";
41"M_D_CPU1_SA_DQS_DP<7>";
42"M_D_CPU1_SB_DQS_DP<6>";
43"M_D_CPU1_SB_DQS_DN<6>";
44"M_D_CPU1_SA_DQS_DN<6>";
45"M_D_CPU1_SB_DQS_DP<5>";
46"M_D_CPU1_SB_DQS_DN<5>";
47"M_D_CPU1_SA_DQS_DP<5>";
48"M_D_CPU1_SA_DQS_DN<5>";
49"M_D_CPU1_SB_DQS_DP<4>";
50"M_D_CPU1_SB_DQS_DN<4>";
51"M_D_CPU1_SA_DQS_DP<4>";
52"M_D_CPU1_SA_DQS_DN<4>";
53"M_D_CPU1_SB_DQS_DP<3>";
54"M_D_CPU1_SB_DQS_DN<3>";
55"M_D_CPU1_SA_DQS_DP<3>";
56"M_D_CPU1_SA_DQS_DN<3>";
57"M_D_CPU1_SB_DQS_DP<2>";
58"M_D_CPU1_SB_DQS_DN<2>";
59"M_D_CPU1_SA_DQS_DP<2>";
60"M_D_CPU1_SA_DQS_DN<2>";
61"M_D_CPU1_SB_DQS_DP<1>";
62"M_D_CPU1_SB_DQS_DN<1>";
63"M_D_CPU1_SA_DQS_DP<1>";
64"M_D_CPU1_SA_DQS_DN<1>";
65"M_D_CPU1_SB_DQS_DP<0>";
66"M_D_CPU1_SB_DQS_DN<0>";
67"M_D_CPU1_SA_DQS_DP<0>";
68"M_D_CPU1_SA_DQS_DN<0>";
69"M_D_CPU1_SB_DQS_DP<7>";
70"M_D_CPU1_SB_DQS_DN<8>";
71"M_D_CPU1_SB_DQS_DP<8>";
72"M_D_CPU1_SA_DQS_DP<6>";
73"M_D_CPU1_SA_DQS_DN<7>";
74"M_D_CPU1_SA_DQ<31>";
75"M_D_CPU1_SB_PAR";
76"M_D_CPU1_SA_PAR";
77"M_D_CPU1_SB_DQ<0>";
78"M_D_CPU1_SB_DQ<1>";
79"M_D_CPU1_SB_DQ<2>";
80"M_D_CPU1_SB_DQ<3>";
81"M_D_CPU1_SB_DQ<4>";
82"M_D_CPU1_SB_DQ<5>";
83"M_D_CPU1_SB_DQ<6>";
84"M_D_CPU1_SB_DQ<7>";
85"M_D_CPU1_SB_DQ<8>";
86"M_D_CPU1_SB_DQ<9>";
87"M_D_CPU1_SB_DQ<10>";
88"M_D_CPU1_SB_DQ<11>";
89"M_D_CPU1_SB_DQ<12>";
90"M_D_CPU1_SB_DQ<13>";
91"M_D_CPU1_SB_DQ<14>";
92"M_D_CPU1_SB_DQ<15>";
93"M_D_CPU1_SB_DQ<18>";
94"M_D_CPU1_SB_DQ<19>";
95"M_D_CPU1_SB_DQ<20>";
96"M_D_CPU1_SB_DQ<21>";
97"M_D_CPU1_SB_DQ<22>";
98"M_D_CPU1_SB_DQ<23>";
99"M_D_CPU1_SB_DQ<24>";
100"M_D_CPU1_SB_DQ<25>";
101"M_D_CPU1_SB_DQ<26>";
102"M_D_CPU1_SB_DQ<27>";
103"M_D_CPU1_SB_DQ<28>";
104"M_D_CPU1_SB_DQ<29>";
105"M_D_CPU1_SB_DQ<30>";
106"M_D_CPU1_SB_DQ<31>";
107"M_D_CPU1_SA_DQ<0>";
108"M_D_CPU1_SA_DQ<1>";
109"M_D_CPU1_SA_DQ<2>";
110"M_D_CPU1_SA_DQ<3>";
111"M_D_CPU1_SA_DQ<4>";
112"M_D_CPU1_SA_DQ<5>";
113"M_D_CPU1_SA_DQ<6>";
114"M_D_CPU1_SA_DQ<7>";
115"M_D_CPU1_SA_DQ<8>";
116"M_D_CPU1_SA_DQ<9>";
117"M_D_CPU1_SA_DQ<10>";
118"M_D_CPU1_SA_DQ<11>";
119"M_D_CPU1_SA_DQ<12>";
120"M_D_CPU1_SA_DQ<13>";
121"M_D_CPU1_SA_DQ<14>";
122"M_D_CPU1_SA_DQ<15>";
123"M_D_CPU1_SA_DQ<16>";
124"M_D_CPU1_SA_DQ<17>";
125"M_D_CPU1_SA_DQ<18>";
126"M_D_CPU1_SA_DQ<19>";
127"M_D_CPU1_SA_DQ<20>";
128"M_D_CPU1_SA_DQ<21>";
129"M_D_CPU1_SA_DQ<22>";
130"M_D_CPU1_SA_DQ<23>";
131"M_D_CPU1_SA_DQ<24>";
132"M_D_CPU1_SA_DQ<25>";
133"M_D_CPU1_SA_DQ<26>";
134"M_D_CPU1_SA_DQ<27>";
135"M_D_CPU1_SA_DQ<28>";
136"M_D_CPU1_SA_DQ<29>";
137"M_D_CPU1_SA_DQ<30>";
138"M_D_CPU1_SB_CS_N<1>";
139"M_D_CPU1_SA_CS_N<1>";
140"M_D_CPU1_SB_CS_N<0>";
141"M_D_CPU1_SA_CS_N<0>";
142"M_D_CPU1_CLK_DP<0>";
143"M_D_CPU1_CLK_DN<0>";
144"M_D_CPU1_SB_CB<2>";
145"M_D_CPU1_SB_CB<3>";
146"M_D_CPU1_SB_CB<4>";
147"M_D_CPU1_SB_CB<5>";
148"M_D_CPU1_SB_CB<6>";
149"M_D_CPU1_SA_CB<0>";
150"M_D_CPU1_SA_CB<2>";
151"M_D_CPU1_SA_CB<3>";
152"M_D_CPU1_SA_CB<5>";
153"M_D_CPU1_SA_CB<6>";
154"M_D_CPU1_SB_CA<6>";
155"M_D_CPU1_SA_CA<6>";
156"M_D_CPU1_SB_CA<5>";
157"M_D_CPU1_SA_CA<5>";
158"M_D_CPU1_SB_CA<4>";
159"M_D_CPU1_SA_CA<4>";
160"M_D_CPU1_SB_CA<3>";
161"M_D_CPU1_SA_CA<3>";
162"M_D_CPU1_SB_CA<2>";
163"M_D_CPU1_SA_CA<2>";
164"M_D_CPU1_SB_CA<1>";
165"M_D_CPU1_SA_CA<1>";
166"M_D_CPU1_SB_CA<0>";
167"M_D_CPU1_SA_CA<0>";
168"M_D_CPU1_SB_CB<7>";
169"M_D_CPU1_SA_CB<1>";
170"M_D_CPU1_SA_CB<4>";
171"M_D_CPU1_SA_CB<7>";
172"PD_CHD_CPU1_DIMM_SAA";
%"TAP"
"1","(-6100,4225)","0","mstr_standard","I107";
;
CDS_LIB"mstr_standard"
BODY_TYPE"PLUMBING"
HDL_TAP"TRUE";
"B \NAC \NWC"8;
"S \NAC"
BN"4"111;
%"TAP"
"1","(-6100,4275)","0","mstr_standard","I108";
;
CDS_LIB"mstr_standard"
BODY_TYPE"PLUMBING"
HDL_TAP"TRUE";
"B \NAC \NWC"8;
"S \NAC"
BN"5"112;
%"TAP"
"1","(-6100,4325)","0","mstr_standard","I109";
;
CDS_LIB"mstr_standard"
BODY_TYPE"PLUMBING"
HDL_TAP"TRUE";
"B \NAC \NWC"8;
"S \NAC"
BN"6"113;
%"TAP"
"1","(-6100,4375)","0","mstr_standard","I110";
;
CDS_LIB"mstr_standard"
BODY_TYPE"PLUMBING"
HDL_TAP"TRUE";
"B \NAC \NWC"8;
"S \NAC"
BN"7"114;
%"TAP"
"1","(-6100,4425)","0","mstr_standard","I111";
;
CDS_LIB"mstr_standard"
BODY_TYPE"PLUMBING"
HDL_TAP"TRUE";
"B \NAC \NWC"8;
"S \NAC"
BN"8"115;
%"TAP"
"1","(-6100,4475)","0","mstr_standard","I112";
;
CDS_LIB"mstr_standard"
BODY_TYPE"PLUMBING"
HDL_TAP"TRUE";
"B \NAC \NWC"8;
"S \NAC"
BN"9"116;
%"TAP"
"1","(-6100,4575)","0","mstr_standard","I113";
;
CDS_LIB"mstr_standard"
BODY_TYPE"PLUMBING"
HDL_TAP"TRUE";
"B \NAC \NWC"8;
"S \NAC"
BN"11"118;
%"TAP"
"1","(-6100,4525)","0","mstr_standard","I114";
;
CDS_LIB"mstr_standard"
BODY_TYPE"PLUMBING"
HDL_TAP"TRUE";
"B \NAC \NWC"8;
"S \NAC"
BN"10"117;
%"TAP"
"1","(-6100,4625)","0","mstr_standard","I115";
;
CDS_LIB"mstr_standard"
BODY_TYPE"PLUMBING"
HDL_TAP"TRUE";
"B \NAC \NWC"8;
"S \NAC"
BN"12"119;
%"TAP"
"1","(-6100,4675)","0","mstr_standard","I116";
;
CDS_LIB"mstr_standard"
BODY_TYPE"PLUMBING"
HDL_TAP"TRUE";
"B \NAC \NWC"8;
"S \NAC"
BN"13"120;
%"TAP"
"1","(-6100,4725)","0","mstr_standard","I117";
;
CDS_LIB"mstr_standard"
BODY_TYPE"PLUMBING"
HDL_TAP"TRUE";
"B \NAC \NWC"8;
"S \NAC"
BN"14"121;
%"TAP"
"1","(-6100,4825)","0","mstr_standard","I118";
;
CDS_LIB"mstr_standard"
BODY_TYPE"PLUMBING"
HDL_TAP"TRUE";
"B \NAC \NWC"8;
"S \NAC"
BN"16"123;
%"TAP"
"1","(-6100,4775)","0","mstr_standard","I119";
;
CDS_LIB"mstr_standard"
BODY_TYPE"PLUMBING"
HDL_TAP"TRUE";
"B \NAC \NWC"8;
"S \NAC"
BN"15"122;
%"TAP"
"1","(-7800,3425)","2","mstr_standard","I12";
;
CDS_LIB"mstr_standard"
BODY_TYPE"PLUMBING"
HDL_TAP"TRUE";
"B \NAC \NWC"5;
"S \NAC"
BN"1"23;
%"TAP"
"1","(-6100,4875)","0","mstr_standard","I120";
;
CDS_LIB"mstr_standard"
BODY_TYPE"PLUMBING"
HDL_TAP"TRUE";
"B \NAC \NWC"8;
"S \NAC"
BN"17"124;
%"TAP"
"1","(-6100,4925)","0","mstr_standard","I121";
;
CDS_LIB"mstr_standard"
BODY_TYPE"PLUMBING"
HDL_TAP"TRUE";
"B \NAC \NWC"8;
"S \NAC"
BN"18"125;
%"TAP"
"1","(-6100,5025)","0","mstr_standard","I122";
;
CDS_LIB"mstr_standard"
BODY_TYPE"PLUMBING"
HDL_TAP"TRUE";
"B \NAC \NWC"8;
"S \NAC"
BN"20"127;
%"TAP"
"1","(-6100,4975)","0","mstr_standard","I123";
;
CDS_LIB"mstr_standard"
BODY_TYPE"PLUMBING"
HDL_TAP"TRUE";
"B \NAC \NWC"8;
"S \NAC"
BN"19"126;
%"TAP"
"1","(-6100,5075)","0","mstr_standard","I124";
;
CDS_LIB"mstr_standard"
BODY_TYPE"PLUMBING"
HDL_TAP"TRUE";
"B \NAC \NWC"8;
"S \NAC"
BN"21"128;
%"TAP"
"1","(-6100,5125)","0","mstr_standard","I125";
;
CDS_LIB"mstr_standard"
BODY_TYPE"PLUMBING"
HDL_TAP"TRUE";
"B \NAC \NWC"8;
"S \NAC"
BN"22"129;
%"TAP"
"1","(-6100,5175)","0","mstr_standard","I126";
;
CDS_LIB"mstr_standard"
BODY_TYPE"PLUMBING"
HDL_TAP"TRUE";
"B \NAC \NWC"8;
"S \NAC"
BN"23"130;
%"TAP"
"1","(-6100,5275)","0","mstr_standard","I127";
;
CDS_LIB"mstr_standard"
BODY_TYPE"PLUMBING"
HDL_TAP"TRUE";
"B \NAC \NWC"8;
"S \NAC"
BN"25"132;
%"TAP"
"1","(-6100,5225)","0","mstr_standard","I128";
;
CDS_LIB"mstr_standard"
BODY_TYPE"PLUMBING"
HDL_TAP"TRUE";
"B \NAC \NWC"8;
"S \NAC"
BN"24"131;
%"TAP"
"1","(-6100,5325)","0","mstr_standard","I129";
;
CDS_LIB"mstr_standard"
BODY_TYPE"PLUMBING"
HDL_TAP"TRUE";
"B \NAC \NWC"8;
"S \NAC"
BN"26"133;
%"TAP"
"1","(-7800,3375)","2","mstr_standard","I13";
;
CDS_LIB"mstr_standard"
BODY_TYPE"PLUMBING"
HDL_TAP"TRUE";
"B \NAC \NWC"5;
"S \NAC"
BN"0"14;
%"TAP"
"1","(-6100,5375)","0","mstr_standard","I130";
;
CDS_LIB"mstr_standard"
BODY_TYPE"PLUMBING"
HDL_TAP"TRUE";
"B \NAC \NWC"8;
"S \NAC"
BN"27"134;
%"TAP"
"1","(-6100,5475)","0","mstr_standard","I131";
;
CDS_LIB"mstr_standard"
BODY_TYPE"PLUMBING"
HDL_TAP"TRUE";
"B \NAC \NWC"8;
"S \NAC"
BN"29"136;
%"TAP"
"1","(-6100,5425)","0","mstr_standard","I132";
;
CDS_LIB"mstr_standard"
BODY_TYPE"PLUMBING"
HDL_TAP"TRUE";
"B \NAC \NWC"8;
"S \NAC"
BN"28"135;
%"TAP"
"1","(-6100,5525)","0","mstr_standard","I133";
;
CDS_LIB"mstr_standard"
BODY_TYPE"PLUMBING"
HDL_TAP"TRUE";
"B \NAC \NWC"8;
"S \NAC"
BN"30"137;
%"TAP"
"1","(-6100,5575)","0","mstr_standard","I134";
;
CDS_LIB"mstr_standard"
BODY_TYPE"PLUMBING"
HDL_TAP"TRUE";
"B \NAC \NWC"8;
"S \NAC"
BN"31"74;
%"TAP"
"1","(-7800,3525)","2","mstr_standard","I14";
;
CDS_LIB"mstr_standard"
BODY_TYPE"PLUMBING"
HDL_TAP"TRUE";
"B \NAC \NWC"5;
"S \NAC"
BN"3"145;
%"GND"
"1","(-6525,1200)","0","mstr_symbols","I145";
;
VOLTAGE"0.0"
CDS_LIB"mstr_symbols"
BOM_COST"MEM"
SIZE"1B"
BODY_TYPE"PLUMBING"
HDL_POWER"GND";
"A\NAC"1;
%"Q_RES"
"2","(-6525,1425)","0","pure_quanta","I146";
;
LOCATION"R772"
$SEC"1"
CDS_SEC"1"
PACK_TYPE"0402LF"
VALUE"35.7K"
TOLERANCE"1%"
MATERIAL"CHIP"
WATTAGE"1/16W"
CDS_LIB"pure_quanta"
PART_NUMBER"CS33572FB01";
"A"
$PN"1"172;
"B"
$PN"2"1;
%"GND"
"1","(-2200,2000)","0","mstr_symbols","I147";
;
VOLTAGE"0.0"
SIZE"1B"
CDS_LIB"mstr_symbols"
BODY_TYPE"PLUMBING"
HDL_POWER"GND";
"A\NAC"33;
%"TAP"
"1","(-7800,3475)","2","mstr_standard","I15";
;
CDS_LIB"mstr_standard"
BODY_TYPE"PLUMBING"
HDL_TAP"TRUE";
"B \NAC \NWC"5;
"S \NAC"
BN"2"144;
%"TAP"
"1","(-7800,3625)","2","mstr_standard","I16";
;
CDS_LIB"mstr_standard"
BODY_TYPE"PLUMBING"
HDL_TAP"TRUE";
"B \NAC \NWC"5;
"S \NAC"
BN"5"147;
%"SCONN288_DDR506112002KQ"
"3","(-1300,3750)","0","pure_quanta","I161";
;
LOCATION"J30"
$SEC"3"
CDS_SEC"3"
VALUE"SCONN288_DDR506112002KQ"
MATERIAL"IO"
PART_TYPE"SMLF"
CDS_LIB"pure_quanta"
NEEDS_NO_SIZE"TRUE"
CDS_LMAN_SYM_OUTLINE"-450,1800,450,-1750"
PART_NUMBER"DFHST8FS479";
"G3"
$PN"G3"32;
"G2"
$PN"G2"32;
"G1"
$PN"G1"32;
"VSS62"
$PN"141"32;
"VSS61"
$PN"139"32;
"VSS60"
$PN"136"32;
"VSS58"
$PN"132"32;
"VSS104"
$PN"240"33;
"VSS102"
$PN"235"33;
"VSS100"
$PN"230"33;
"VIN_BULK2"
$PN"146"30;
"VIN_BULK1"
$PN"145"30;
"VIN_BULK0"
$PN"1"30;
"VSS126"
$PN"288"33;
"VSS125"
$PN"286"33;
"VSS124"
$PN"284"33;
"VSS123"
$PN"281"33;
"VSS122"
$PN"279"33;
"VSS121"
$PN"277"33;
"VSS120"
$PN"275"33;
"VSS119"
$PN"273"33;
"VSS118"
$PN"270"33;
"VSS117"
$PN"268"33;
"VSS116"
$PN"266"33;
"VSS115"
$PN"264"33;
"VSS114"
$PN"262"33;
"VSS113"
$PN"259"33;
"VSS112"
$PN"257"33;
"VSS111"
$PN"255"33;
"VSS110"
$PN"253"33;
"VSS109"
$PN"251"33;
"VSS108"
$PN"248"33;
"VSS107"
$PN"246"33;
"VSS106"
$PN"244"33;
"VSS105"
$PN"242"33;
"VSS103"
$PN"237"33;
"VSS101"
$PN"233"33;
"VSS99"
$PN"228"33;
"VSS98"
$PN"226"33;
"VSS97"
$PN"224"33;
"VSS96"
$PN"222"33;
"VSS95"
$PN"219"33;
"VSS94"
$PN"216"33;
"VSS93"
$PN"214"33;
"VSS92"
$PN"212"33;
"VSS91"
$PN"210"33;
"VSS90"
$PN"208"33;
"VSS89"
$PN"206"33;
"VSS88"
$PN"204"33;
"VSS87"
$PN"202"33;
"VSS86"
$PN"199"33;
"VSS85"
$PN"197"33;
"VSS84"
$PN"195"33;
"VSS83"
$PN"193"33;
"VSS82"
$PN"191"33;
"VSS81"
$PN"188"33;
"VSS80"
$PN"186"33;
"VSS79"
$PN"184"33;
"VSS78"
$PN"182"33;
"VSS77"
$PN"180"33;
"VSS76"
$PN"177"33;
"VSS75"
$PN"175"33;
"VSS74"
$PN"173"33;
"VSS73"
$PN"171"33;
"VSS72"
$PN"169"33;
"VSS71"
$PN"166"33;
"VSS70"
$PN"164"33;
"VSS69"
$PN"162"33;
"VSS68"
$PN"160"33;
"VSS67"
$PN"158"33;
"VSS66"
$PN"155"33;
"VSS65"
$PN"153"33;
"VSS64"
$PN"151"33;
"VSS63"
$PN"143"32;
"VSS59"
$PN"134"32;
"VSS57"
$PN"130"32;
"VSS56"
$PN"128"32;
"VSS55"
$PN"125"32;
"VSS54"
$PN"123"32;
"VSS53"
$PN"121"32;
"VSS52"
$PN"119"32;
"VSS51"
$PN"117"32;
"VSS50"
$PN"114"32;
"VSS49"
$PN"112"32;
"VSS48"
$PN"110"32;
"VSS47"
$PN"108"32;
"VSS46"
$PN"106"32;
"VSS45"
$PN"103"32;
"VSS44"
$PN"101"32;
"VSS43"
$PN"99"32;
"VSS42"
$PN"97"32;
"VSS41"
$PN"95"32;
"VSS40"
$PN"92"32;
"VSS39"
$PN"90"32;
"VSS38"
$PN"88"32;
"VSS37"
$PN"85"32;
"VSS36"
$PN"83"32;
"VSS35"
$PN"81"32;
"VSS34"
$PN"79"32;
"VSS33"
$PN"77"32;
"VSS32"
$PN"75"32;
"VSS31"
$PN"73"32;
"VSS30"
$PN"71"32;
"VSS29"
$PN"69"32;
"VSS28"
$PN"67"32;
"VSS27"
$PN"65"32;
"VSS26"
$PN"63"32;
"VSS25"
$PN"61"32;
"VSS24"
$PN"59"32;
"VSS23"
$PN"57"32;
"VSS22"
$PN"54"32;
"VSS21"
$PN"52"32;
"VSS20"
$PN"50"32;
"VSS19"
$PN"48"32;
"VSS18"
$PN"46"32;
"VSS17"
$PN"43"32;
"VSS16"
$PN"41"32;
"VSS15"
$PN"39"32;
"VSS14"
$PN"37"32;
"VSS13"
$PN"35"32;
"VSS12"
$PN"32"32;
"VSS11"
$PN"30"32;
"VSS10"
$PN"28"32;
"VSS9"
$PN"26"32;
"VSS8"
$PN"24"32;
"VSS7"
$PN"21"32;
"VSS6"
$PN"19"32;
"VSS5"
$PN"17"32;
"VSS4"
$PN"15"32;
"VSS3"
$PN"13"32;
"VSS2"
$PN"10"32;
"VSS1"
$PN"8"32;
"VSS0"
$PN"6"32;
%"GND"
"1","(-400,1800)","0","mstr_symbols","I162";
;
VOLTAGE"0.0"
CDS_LIB"mstr_symbols"
SIZE"1B"
BODY_TYPE"PLUMBING"
HDL_POWER"GND";
"A\NAC"32;
%"TAP"
"1","(-7800,3575)","2","mstr_standard","I17";
;
CDS_LIB"mstr_standard"
BODY_TYPE"PLUMBING"
HDL_TAP"TRUE";
"B \NAC \NWC"5;
"S \NAC"
BN"4"146;
%"TAP"
"1","(-7800,3675)","2","mstr_standard","I18";
;
CDS_LIB"mstr_standard"
BODY_TYPE"PLUMBING"
HDL_TAP"TRUE";
"B \NAC \NWC"5;
"S \NAC"
BN"6"148;
%"Q_CAP"
"1","(-8750,3400)","2","pure_quanta","I185";
;
LOCATION"C148"
$SEC"1"
CDS_SEC"1"
TOLERANCE"10%"
MATERIAL"X7R"
VOLTAGE"25V"
VALUE"0.1UF"
PACK_TYPE"0402"
CDS_LIB"pure_quanta"
BOM_COST"MEM"
ROOM""
PART_NUMBER"CH4104K1B00";
"B"
$PN"2"2;
"A"
$PN"1"16;
%"GND"
"1","(-8750,3175)","0","mstr_symbols","I186";
;
ROOM"MEM_EFGH_DECOUPLING_CAPS"
VOLTAGE"0"
BOM_COST"MEM"
SIZE"1B"
CDS_LIB"mstr_symbols"
BODY_TYPE"PLUMBING"
HDL_POWER"GND";
"A\NAC"2;
%"Q_RES"
"1","(-8600,2325)","2","pure_quanta","I188";
;
LOCATION"R306"
$SEC"1"
CDS_SEC"1"
VALUE"1K"
PACK_TYPE"0402LF"
MATERIAL"CHIP"
WATTAGE"1/16W"
BOM_COST"MEM"
CDS_LIB"pure_quanta"
TOLERANCE"1%"
ROOM""
PART_NUMBER"CS21002FB06";
"B"
$PN"2"27;
"A"
$PN"1"26;
%"VCC_CORE"
"1","(-8475,2650)","0","mstr_symbols","I189";
;
HDL_POWER"P3V3"
ROOM"PVCCINFAON_CPU0_CTRL"
VOLTAGE"3.3"
CDS_LIB"mstr_symbols";
"A"3;
%"TAP"
"1","(-7800,3875)","2","mstr_standard","I19";
;
CDS_LIB"mstr_standard"
BODY_TYPE"PLUMBING"
HDL_TAP"TRUE";
"B \NAC \NWC"4;
"S \NAC"
BN"1"169;
%"Q_RES"
"2","(-8475,2475)","0","pure_quanta","I190";
;
LOCATION"R106"
$SEC"1"
CDS_SEC"1"
WATTAGE"1/16W"
MATERIAL"EMPTY"
PACK_TYPE"0402LF"
VALUE"1K"
TOLERANCE"1%"
CDS_LIB"pure_quanta"
BOM_COST"MEM"
ROOM""
PART_NUMBER"CS21002FB06";
"A"
$PN"1"3;
"B"
$PN"2"26;
%"TAP"
"1","(-3275,3875)","0","mstr_standard","I191";
;
CDS_LIB"mstr_standard"
BODY_TYPE"PLUMBING"
HDL_TAP"TRUE";
"B \NAC \NWC"10;
"S \NAC"
BN"1"64;
%"TAP"
"1","(-3275,3975)","0","mstr_standard","I192";
;
CDS_LIB"mstr_standard"
BODY_TYPE"PLUMBING"
HDL_TAP"TRUE";
"B \NAC \NWC"10;
"S \NAC"
BN"2"60;
%"TAP"
"1","(-3475,4025)","0","mstr_standard","I193";
;
CDS_LIB"mstr_standard"
BODY_TYPE"PLUMBING"
HDL_TAP"TRUE";
"B \NAC \NWC"11;
"S \NAC"
BN"2"59;
%"TAP"
"1","(-3475,4125)","0","mstr_standard","I194";
;
CDS_LIB"mstr_standard"
BODY_TYPE"PLUMBING"
HDL_TAP"TRUE";
"B \NAC \NWC"11;
"S \NAC"
BN"3"55;
%"TAP"
"1","(-3275,4675)","0","mstr_standard","I198";
;
CDS_LIB"mstr_standard"
BODY_TYPE"PLUMBING"
HDL_TAP"TRUE";
"B \NAC \NWC"10;
"S \NAC"
BN"9"37;
%"TAP"
"1","(-3275,4575)","0","mstr_standard","I199";
;
CDS_LIB"mstr_standard"
BODY_TYPE"PLUMBING"
HDL_TAP"TRUE";
"B \NAC \NWC"10;
"S \NAC"
BN"8"39;
%"TAP"
"1","(-7800,3825)","2","mstr_standard","I20";
;
CDS_LIB"mstr_standard"
BODY_TYPE"PLUMBING"
HDL_TAP"TRUE";
"B \NAC \NWC"4;
"S \NAC"
BN"0"149;
%"TAP"
"1","(-3275,4475)","0","mstr_standard","I200";
;
CDS_LIB"mstr_standard"
BODY_TYPE"PLUMBING"
HDL_TAP"TRUE";
"B \NAC \NWC"10;
"S \NAC"
BN"7"73;
%"TAP"
"1","(-3275,4375)","0","mstr_standard","I201";
;
CDS_LIB"mstr_standard"
BODY_TYPE"PLUMBING"
HDL_TAP"TRUE";
"B \NAC \NWC"10;
"S \NAC"
BN"6"44;
%"TAP"
"1","(-3475,4625)","0","mstr_standard","I202";
;
CDS_LIB"mstr_standard"
BODY_TYPE"PLUMBING"
HDL_TAP"TRUE";
"B \NAC \NWC"11;
"S \NAC"
BN"8"38;
%"TAP"
"1","(-3475,4725)","0","mstr_standard","I203";
;
CDS_LIB"mstr_standard"
BODY_TYPE"PLUMBING"
HDL_TAP"TRUE";
"B \NAC \NWC"11;
"S \NAC"
BN"9"36;
%"TAP"
"1","(-3475,4425)","0","mstr_standard","I204";
;
CDS_LIB"mstr_standard"
BODY_TYPE"PLUMBING"
HDL_TAP"TRUE";
"B \NAC \NWC"11;
"S \NAC"
BN"6"72;
%"TAP"
"1","(-3475,4525)","0","mstr_standard","I205";
;
CDS_LIB"mstr_standard"
BODY_TYPE"PLUMBING"
HDL_TAP"TRUE";
"B \NAC \NWC"11;
"S \NAC"
BN"7"41;
%"TAP"
"1","(-3475,4325)","0","mstr_standard","I206";
;
CDS_LIB"mstr_standard"
BODY_TYPE"PLUMBING"
HDL_TAP"TRUE";
"B \NAC \NWC"11;
"S \NAC"
BN"5"47;
%"TAP"
"1","(-3275,4275)","0","mstr_standard","I207";
;
CDS_LIB"mstr_standard"
BODY_TYPE"PLUMBING"
HDL_TAP"TRUE";
"B \NAC \NWC"10;
"S \NAC"
BN"5"48;
%"TAP"
"1","(-3275,4175)","0","mstr_standard","I208";
;
CDS_LIB"mstr_standard"
BODY_TYPE"PLUMBING"
HDL_TAP"TRUE";
"B \NAC \NWC"10;
"S \NAC"
BN"4"52;
%"TAP"
"1","(-3275,4075)","0","mstr_standard","I209";
;
CDS_LIB"mstr_standard"
BODY_TYPE"PLUMBING"
HDL_TAP"TRUE";
"B \NAC \NWC"10;
"S \NAC"
BN"3"56;
%"TAP"
"1","(-7800,3725)","2","mstr_standard","I21";
;
CDS_LIB"mstr_standard"
BODY_TYPE"PLUMBING"
HDL_TAP"TRUE";
"B \NAC \NWC"5;
"S \NAC"
BN"7"168;
%"TAP"
"1","(-3475,4225)","0","mstr_standard","I210";
;
CDS_LIB"mstr_standard"
BODY_TYPE"PLUMBING"
HDL_TAP"TRUE";
"B \NAC \NWC"11;
"S \NAC"
BN"4"51;
%"TAP"
"1","(-3475,3925)","0","mstr_standard","I211";
;
CDS_LIB"mstr_standard"
BODY_TYPE"PLUMBING"
HDL_TAP"TRUE";
"B \NAC \NWC"11;
"S \NAC"
BN"1"63;
%"TAP"
"1","(-3475,3825)","0","mstr_standard","I212";
;
CDS_LIB"mstr_standard"
BODY_TYPE"PLUMBING"
HDL_TAP"TRUE";
"B \NAC \NWC"11;
"S \NAC"
BN"0"67;
%"TAP"
"1","(-3275,3625)","0","mstr_standard","I215";
;
CDS_LIB"mstr_standard"
BODY_TYPE"PLUMBING"
HDL_TAP"TRUE";
"B \NAC \NWC"13;
"S \NAC"
BN"9"35;
%"TAP"
"1","(-3275,3775)","0","mstr_standard","I216";
;
CDS_LIB"mstr_standard"
BODY_TYPE"PLUMBING"
HDL_TAP"TRUE";
"B \NAC \NWC"10;
"S \NAC"
BN"0"68;
%"TAP"
"1","(-3275,3525)","0","mstr_standard","I217";
;
CDS_LIB"mstr_standard"
BODY_TYPE"PLUMBING"
HDL_TAP"TRUE";
"B \NAC \NWC"13;
"S \NAC"
BN"8"70;
%"TAP"
"1","(-3275,3425)","0","mstr_standard","I218";
;
CDS_LIB"mstr_standard"
BODY_TYPE"PLUMBING"
HDL_TAP"TRUE";
"B \NAC \NWC"13;
"S \NAC"
BN"7"40;
%"TAP"
"1","(-3275,3325)","0","mstr_standard","I219";
;
CDS_LIB"mstr_standard"
BODY_TYPE"PLUMBING"
HDL_TAP"TRUE";
"B \NAC \NWC"13;
"S \NAC"
BN"6"43;
%"TAP"
"1","(-7800,3925)","2","mstr_standard","I22";
;
CDS_LIB"mstr_standard"
BODY_TYPE"PLUMBING"
HDL_TAP"TRUE";
"B \NAC \NWC"4;
"S \NAC"
BN"2"150;
%"TAP"
"1","(-3475,3575)","0","mstr_standard","I220";
;
CDS_LIB"mstr_standard"
BODY_TYPE"PLUMBING"
HDL_TAP"TRUE";
"B \NAC \NWC"12;
"S \NAC"
BN"8"71;
%"TAP"
"1","(-3475,3675)","0","mstr_standard","I221";
;
CDS_LIB"mstr_standard"
BODY_TYPE"PLUMBING"
HDL_TAP"TRUE";
"B \NAC \NWC"12;
"S \NAC"
BN"9"34;
%"TAP"
"1","(-3475,3375)","0","mstr_standard","I222";
;
CDS_LIB"mstr_standard"
BODY_TYPE"PLUMBING"
HDL_TAP"TRUE";
"B \NAC \NWC"12;
"S \NAC"
BN"6"42;
%"TAP"
"1","(-3475,3475)","0","mstr_standard","I223";
;
CDS_LIB"mstr_standard"
BODY_TYPE"PLUMBING"
HDL_TAP"TRUE";
"B \NAC \NWC"12;
"S \NAC"
BN"7"69;
%"TAP"
"1","(-3275,3225)","0","mstr_standard","I224";
;
CDS_LIB"mstr_standard"
BODY_TYPE"PLUMBING"
HDL_TAP"TRUE";
"B \NAC \NWC"13;
"S \NAC"
BN"5"46;
%"TAP"
"1","(-3275,3125)","0","mstr_standard","I225";
;
CDS_LIB"mstr_standard"
BODY_TYPE"PLUMBING"
HDL_TAP"TRUE";
"B \NAC \NWC"13;
"S \NAC"
BN"4"50;
%"TAP"
"1","(-3275,3025)","0","mstr_standard","I226";
;
CDS_LIB"mstr_standard"
BODY_TYPE"PLUMBING"
HDL_TAP"TRUE";
"B \NAC \NWC"13;
"S \NAC"
BN"3"54;
%"TAP"
"1","(-3275,2925)","0","mstr_standard","I227";
;
CDS_LIB"mstr_standard"
BODY_TYPE"PLUMBING"
HDL_TAP"TRUE";
"B \NAC \NWC"13;
"S \NAC"
BN"2"58;
%"TAP"
"1","(-3275,2825)","0","mstr_standard","I228";
;
CDS_LIB"mstr_standard"
BODY_TYPE"PLUMBING"
HDL_TAP"TRUE";
"B \NAC \NWC"13;
"S \NAC"
BN"1"62;
%"TAP"
"1","(-3475,3075)","0","mstr_standard","I229";
;
CDS_LIB"mstr_standard"
BODY_TYPE"PLUMBING"
HDL_TAP"TRUE";
"B \NAC \NWC"12;
"S \NAC"
BN"3"53;
%"TAP"
"1","(-7800,3975)","2","mstr_standard","I23";
;
CDS_LIB"mstr_standard"
BODY_TYPE"PLUMBING"
HDL_TAP"TRUE";
"B \NAC \NWC"4;
"S \NAC"
BN"3"151;
%"TAP"
"1","(-3475,3275)","0","mstr_standard","I230";
;
CDS_LIB"mstr_standard"
BODY_TYPE"PLUMBING"
HDL_TAP"TRUE";
"B \NAC \NWC"12;
"S \NAC"
BN"5"45;
%"TAP"
"1","(-3475,3175)","0","mstr_standard","I231";
;
CDS_LIB"mstr_standard"
BODY_TYPE"PLUMBING"
HDL_TAP"TRUE";
"B \NAC \NWC"12;
"S \NAC"
BN"4"49;
%"TAP"
"1","(-3475,2775)","0","mstr_standard","I232";
;
CDS_LIB"mstr_standard"
BODY_TYPE"PLUMBING"
HDL_TAP"TRUE";
"B \NAC \NWC"12;
"S \NAC"
BN"0"65;
%"TAP"
"1","(-3475,2875)","0","mstr_standard","I233";
;
CDS_LIB"mstr_standard"
BODY_TYPE"PLUMBING"
HDL_TAP"TRUE";
"B \NAC \NWC"12;
"S \NAC"
BN"1"61;
%"TAP"
"1","(-3475,2975)","0","mstr_standard","I234";
;
CDS_LIB"mstr_standard"
BODY_TYPE"PLUMBING"
HDL_TAP"TRUE";
"B \NAC \NWC"12;
"S \NAC"
BN"2"57;
%"TAP"
"1","(-3275,2725)","0","mstr_standard","I235";
;
CDS_LIB"mstr_standard"
BODY_TYPE"PLUMBING"
HDL_TAP"TRUE";
"B \NAC \NWC"13;
"S \NAC"
BN"0"66;
%"SCONN288_DDR506112002KQ"
"2","(-4425,3725)","0","pure_quanta","I236";
;
LOCATION"J30"
$SEC"2"
CDS_SEC"2"
MATERIAL"IO"
VALUE"SCONN288_DDR506112002KQ"
PART_TYPE"SMLF"
CDS_LIB"pure_quanta"
NEEDS_NO_SIZE"TRUE"
CDS_LMAN_SYM_OUTLINE"-600,1150,600,-1150"
PART_NUMBER"DFHST8FS479";
"DQS7_A_C||TDQS7_A_C \B"
$PN"178"73;
"DQS6_A_T||TDQS6_A_T"
$PN"168"72;
"DQS8_B_T||TDQS8_B_T"
$PN"283"71;
"DQS8_B_C||TDQS8_B_C \B"
$PN"282"70;
"DQS7_B_T||TDQS7_B_T"
$PN"272"69;
"DQS0_A_C \B"
$PN"12"68;
"DQS0_A_T"
$PN"11"67;
"DQS0_B_C \B"
$PN"105"66;
"DQS0_B_T"
$PN"104"65;
"DQS1_A_C \B"
$PN"23"64;
"DQS1_A_T"
$PN"22"63;
"DQS1_B_C \B"
$PN"116"62;
"DQS1_B_T"
$PN"115"61;
"DQS2_A_C \B"
$PN"34"60;
"DQS2_A_T"
$PN"33"59;
"DQS2_B_C \B"
$PN"127"58;
"DQS2_B_T"
$PN"126"57;
"DQS3_A_C \B"
$PN"45"56;
"DQS3_A_T"
$PN"44"55;
"DQS3_B_C \B"
$PN"138"54;
"DQS3_B_T"
$PN"137"53;
"DQS4_A_C \B"
$PN"56"52;
"DQS4_A_T"
$PN"55"51;
"DQS4_B_C \B"
$PN"238"50;
"DQS4_B_T"
$PN"239"49;
"DQS5_A_C||TDQS5_A_C||DQS5_A_T||TDQS5_A_T \B"
$PN"156"48;
"DQS5_A_T||TDQS5_A_T"
$PN"157"47;
"DQS5_B_C||TDQS5_B_C \B"
$PN"249"46;
"DQS5_B_T||TDQS5_B_T"
$PN"250"45;
"DQS6_A_C||TDQS6_A_C||DQS6_A_T||TDQS6_A_T \B"
$PN"167"44;
"DQS6_B_C||TDQS6_B_C \B"
$PN"260"43;
"DQS6_B_T||TDQS6_B_T"
$PN"261"42;
"DQS7_A_T||TDQS7_A_T"
$PN"179"41;
"DQS7_B_C||TDQS7_B_C \B"
$PN"271"40;
"DQS8_A_C||TDQS8_A_C \B"
$PN"189"39;
"DQS8_A_T||TDQS8_A_T"
$PN"190"38;
"DQS9_A_C||TDQS9_A_C \B"
$PN"200"37;
"DQS9_A_T||TDQS9_A_T"
$PN"201"36;
"DQS9_B_C||TDQS9_B_C \B"
$PN"94"35;
"DQS9_B_T||TDQS9_B_T||DBI4_B_N"
$PN"93"34;
%"GND"
"1","(-2900,5450)","0","pure_quanta_power","I237";
;
ROOM"MEM_EFGH_DECOUPLING_CAPS"
SIZE"1B"
BOM_COST"MEM"
CDS_LIB"pure_quanta_power"
HDL_POWER"GND";
"A<SIZE-1..0>\NAC"31;
%"Q_CAP"
"1","(-2900,5800)","2","pure_quanta","I238";
;
LOCATION"C181"
$SEC"1"
CDS_SEC"1"
MATERIAL"X6S"
TOLERANCE"10%"
VALUE"10UF"
VOLTAGE"25V"
PACK_TYPE"C0805"
BOM_COST"MEM"
CDS_LIB"pure_quanta"
ROOM""
PART_NUMBER"CH6104KEA00";
"B"
$PN"2"31;
"A"
$PN"1"30;
%"Q_CAP"
"1","(-2325,5800)","2","pure_quanta","I239";
;
LOCATION"C182"
$SEC"1"
CDS_SEC"1"
MATERIAL"X6S"
TOLERANCE"10%"
VALUE"10UF"
VOLTAGE"25V"
PACK_TYPE"C0805"
BOM_COST"MEM"
CDS_LIB"pure_quanta"
ROOM""
PART_NUMBER"CH6104KEA00";
"B"
$PN"2"31;
"A"
$PN"1"30;
%"TAP"
"1","(-7800,4025)","2","mstr_standard","I24";
;
CDS_LIB"mstr_standard"
BODY_TYPE"PLUMBING"
HDL_TAP"TRUE";
"B \NAC \NWC"4;
"S \NAC"
BN"4"170;
%"UNIVERSAL_POWER"
"1","(-2900,6125)","0","pure_quanta_power","I240";
;
HDL_POWER"P12V_MEM_CPU1"
CDS_LIB"pure_quanta_power";
"A"30;
%"Q_RES"
"1","(-7850,2800)","0","pure_quanta","I242";
;
LOCATION"R1583"
$SEC"1"
CDS_SEC"1"
VALUE"49.9"
TOLERANCE"1%"
WATTAGE"1/16W"
PACK_TYPE"0402LF"
MATERIAL"CHIP"
CDS_LIB"pure_quanta"
PART_NUMBER"CS04992FB07";
"B"
$PN"2"22;
"A"
$PN"1"19;
%"Q_RES"
"1","(-8225,3025)","0","pure_quanta","I243";
;
LOCATION"R1699"
$SEC"1"
CDS_SEC"1"
MATERIAL"CHIP"
PACK_TYPE"0402LF"
VALUE"10"
TOLERANCE"1%"
WATTAGE"1/16W"
CDS_LIB"pure_quanta"
PART_NUMBER"CS01002FB07";
"B"
$PN"2"18;
"A"
$PN"1"17;
%"TAP"
"1","(-7800,4125)","2","mstr_standard","I25";
;
CDS_LIB"mstr_standard"
BODY_TYPE"PLUMBING"
HDL_TAP"TRUE";
"B \NAC \NWC"4;
"S \NAC"
BN"6"153;
%"TAP"
"1","(-7800,4075)","2","mstr_standard","I26";
;
CDS_LIB"mstr_standard"
BODY_TYPE"PLUMBING"
HDL_TAP"TRUE";
"B \NAC \NWC"4;
"S \NAC"
BN"5"152;
%"TAP"
"1","(-7800,4175)","2","mstr_standard","I27";
;
CDS_LIB"mstr_standard"
BODY_TYPE"PLUMBING"
HDL_TAP"TRUE";
"B \NAC \NWC"4;
"S \NAC"
BN"7"171;
%"TAP"
"1","(-7800,4875)","2","mstr_standard","I37";
;
CDS_LIB"mstr_standard"
BODY_TYPE"PLUMBING"
HDL_TAP"TRUE";
"B \NAC \NWC"7;
"S \NAC"
BN"0"166;
%"TAP"
"1","(-7800,4925)","2","mstr_standard","I38";
;
CDS_LIB"mstr_standard"
BODY_TYPE"PLUMBING"
HDL_TAP"TRUE";
"B \NAC \NWC"7;
"S \NAC"
BN"1"164;
%"TAP"
"1","(-7800,4975)","2","mstr_standard","I39";
;
CDS_LIB"mstr_standard"
BODY_TYPE"PLUMBING"
HDL_TAP"TRUE";
"B \NAC \NWC"7;
"S \NAC"
BN"2"162;
%"TAP"
"1","(-7800,5025)","2","mstr_standard","I40";
;
CDS_LIB"mstr_standard"
BODY_TYPE"PLUMBING"
HDL_TAP"TRUE";
"B \NAC \NWC"7;
"S \NAC"
BN"3"160;
%"TAP"
"1","(-7800,5075)","2","mstr_standard","I41";
;
CDS_LIB"mstr_standard"
BODY_TYPE"PLUMBING"
HDL_TAP"TRUE";
"B \NAC \NWC"7;
"S \NAC"
BN"4"158;
%"TAP"
"1","(-7800,5175)","2","mstr_standard","I42";
;
CDS_LIB"mstr_standard"
BODY_TYPE"PLUMBING"
HDL_TAP"TRUE";
"B \NAC \NWC"7;
"S \NAC"
BN"6"154;
%"TAP"
"1","(-7800,5125)","2","mstr_standard","I43";
;
CDS_LIB"mstr_standard"
BODY_TYPE"PLUMBING"
HDL_TAP"TRUE";
"B \NAC \NWC"7;
"S \NAC"
BN"5"156;
%"TAP"
"1","(-7800,5375)","2","mstr_standard","I45";
;
CDS_LIB"mstr_standard"
BODY_TYPE"PLUMBING"
HDL_TAP"TRUE";
"B \NAC \NWC"6;
"S \NAC"
BN"2"163;
%"TAP"
"1","(-7800,5425)","2","mstr_standard","I46";
;
CDS_LIB"mstr_standard"
BODY_TYPE"PLUMBING"
HDL_TAP"TRUE";
"B \NAC \NWC"6;
"S \NAC"
BN"3"161;
%"TAP"
"1","(-7800,5325)","2","mstr_standard","I47";
;
CDS_LIB"mstr_standard"
BODY_TYPE"PLUMBING"
HDL_TAP"TRUE";
"B \NAC \NWC"6;
"S \NAC"
BN"1"165;
%"TAP"
"1","(-7800,5275)","2","mstr_standard","I48";
;
CDS_LIB"mstr_standard"
BODY_TYPE"PLUMBING"
HDL_TAP"TRUE";
"B \NAC \NWC"6;
"S \NAC"
BN"0"167;
%"TAP"
"1","(-7800,5475)","2","mstr_standard","I49";
;
CDS_LIB"mstr_standard"
BODY_TYPE"PLUMBING"
HDL_TAP"TRUE";
"B \NAC \NWC"6;
"S \NAC"
BN"4"159;
%"TAP"
"1","(-7800,5575)","2","mstr_standard","I50";
;
CDS_LIB"mstr_standard"
BODY_TYPE"PLUMBING"
HDL_TAP"TRUE";
"B \NAC \NWC"6;
"S \NAC"
BN"6"155;
%"TAP"
"1","(-7800,5525)","2","mstr_standard","I51";
;
CDS_LIB"mstr_standard"
BODY_TYPE"PLUMBING"
HDL_TAP"TRUE";
"B \NAC \NWC"6;
"S \NAC"
BN"5"157;
%"SCONN288_DDR506112002KQ"
"1","(-6950,3825)","0","pure_quanta","I52";
;
LOCATION"J30"
$SEC"1"
CDS_SEC"1"
VALUE"SCONN288_DDR506112002KQ"
MATERIAL"IO"
PART_TYPE"SMLF"
CDS_LIB"pure_quanta"
NEEDS_NO_SIZE"TRUE"
CDS_LMAN_SYM_OUTLINE"-450,1900,450,-1850"
PART_NUMBER"DFHST8FS479";
"PWR_GOOD||FAIL_N"
$PN"147"26;
"DQ31_A"
$PN"194"74;
"CB7_A"
$PN"205"171;
"CB4_A"
$PN"58"170;
"CB1_A"
$PN"53"169;
"CB7_B"
$PN"236"168;
"ALERT_N \B"
$PN"62"20;
"CA0_A"
$PN"66"167;
"CA0_B"
$PN"76"166;
"CA1_A"
$PN"211"165;
"CA1_B"
$PN"221"164;
"CA2_A"
$PN"68"163;
"CA2_B"
$PN"78"162;
"CA3_A"
$PN"213"161;
"CA3_B"
$PN"223"160;
"CA4_A"
$PN"70"159;
"CA4_B"
$PN"80"158;
"CA5_A"
$PN"215"157;
"CA5_B"
$PN"225"156;
"CA6_A"
$PN"72"155;
"CA6_B"
$PN"82"154;
"CB6_A"
$PN"203"153;
"CB5_A"
$PN"60"152;
"CB3_A"
$PN"198"151;
"CB2_A"
$PN"196"150;
"CB0_A"
$PN"51"149;
"CB6_B"
$PN"234"148;
"CB5_B"
$PN"91"147;
"CB4_B"
$PN"89"146;
"CB3_B"
$PN"243"145;
"CB2_B"
$PN"241"144;
"CB1_B"
$PN"98"23;
"CB0_B"
$PN"96"14;
"CK_C \B"
$PN"218"143;
"CK_T"
$PN"217"142;
"CS0_A_N"
$PN"64"141;
"CS0_B_N"
$PN"84"140;
"CS1_A_N"
$PN"209"139;
"CS1_B_N"
$PN"229"138;
"DQ30_A"
$PN"192"137;
"DQ29_A"
$PN"49"136;
"DQ28_A"
$PN"47"135;
"DQ27_A"
$PN"187"134;
"DQ26_A"
$PN"185"133;
"DQ25_A"
$PN"42"132;
"DQ24_A"
$PN"40"131;
"DQ23_A"
$PN"183"130;
"DQ22_A"
$PN"181"129;
"DQ21_A"
$PN"38"128;
"DQ20_A"
$PN"36"127;
"DQ19_A"
$PN"176"126;
"DQ18_A"
$PN"174"125;
"DQ17_A"
$PN"31"124;
"DQ16_A"
$PN"29"123;
"DQ15_A"
$PN"172"122;
"DQ14_A"
$PN"170"121;
"DQ13_A"
$PN"27"120;
"DQ12_A"
$PN"25"119;
"DQ11_A"
$PN"165"118;
"DQ10_A"
$PN"163"117;
"DQ9_A"
$PN"20"116;
"DQ8_A"
$PN"18"115;
"DQ7_A"
$PN"161"114;
"DQ6_A"
$PN"159"113;
"DQ5_A"
$PN"16"112;
"DQ4_A"
$PN"14"111;
"DQ3_A"
$PN"154"110;
"DQ2_A"
$PN"152"109;
"DQ1_A"
$PN"9"108;
"DQ0_A"
$PN"7"107;
"DQ31_B"
$PN"287"106;
"DQ30_B"
$PN"285"105;
"DQ29_B"
$PN"142"104;
"DQ28_B"
$PN"140"103;
"DQ27_B"
$PN"280"102;
"DQ26_B"
$PN"278"101;
"DQ25_B"
$PN"135"100;
"DQ24_B"
$PN"133"99;
"DQ23_B"
$PN"276"98;
"DQ22_B"
$PN"274"97;
"DQ21_B"
$PN"131"96;
"DQ20_B"
$PN"129"95;
"DQ19_B"
$PN"269"94;
"DQ18_B"
$PN"267"93;
"DQ17_B"
$PN"124"25;
"DQ16_B"
$PN"122"24;
"DQ15_B"
$PN"265"92;
"DQ14_B"
$PN"263"91;
"DQ13_B"
$PN"120"90;
"DQ12_B"
$PN"118"89;
"DQ11_B"
$PN"258"88;
"DQ10_B"
$PN"256"87;
"DQ9_B"
$PN"113"86;
"DQ8_B"
$PN"111"85;
"DQ7_B"
$PN"254"84;
"DQ6_B"
$PN"252"83;
"DQ5_B"
$PN"109"82;
"DQ4_B"
$PN"107"81;
"DQ3_B"
$PN"247"80;
"DQ2_B"
$PN"245"79;
"DQ1_B"
$PN"102"78;
"DQ0_B"
$PN"100"77;
"HAS"
$PN"148"15;
"HSCL"
$PN"4"22;
"HSDA"
$PN"5"18;
"LBD||RSP_A_N"
$PN"86"28;
"LBS||RSP_B_N"
$PN"87"29;
"PAR_A"
$PN"74"76;
"PAR_B"
$PN"227"75;
"RESET_N \B"
$PN"207"21;
"RFU6"
$PN"232"0;
"RFU5"
$PN"231"0;
"RFU4"
$PN"220"0;
"RFU3"
$PN"150"0;
"RFU2"
$PN"149"0;
"RFU1"
$PN"144"0;
"RFU0"
$PN"2"0;
"VIN_MGMT"
$PN"3"16;
%"TAP"
"1","(-6100,2375)","0","mstr_standard","I53";
;
CDS_LIB"mstr_standard"
BODY_TYPE"PLUMBING"
HDL_TAP"TRUE";
"B \NAC \NWC"9;
"S \NAC"
BN"0"77;
%"TAP"
"1","(-6100,2425)","0","mstr_standard","I54";
;
CDS_LIB"mstr_standard"
BODY_TYPE"PLUMBING"
HDL_TAP"TRUE";
"B \NAC \NWC"9;
"S \NAC"
BN"1"78;
%"TAP"
"1","(-6100,2525)","0","mstr_standard","I55";
;
CDS_LIB"mstr_standard"
BODY_TYPE"PLUMBING"
HDL_TAP"TRUE";
"B \NAC \NWC"9;
"S \NAC"
BN"3"80;
%"TAP"
"1","(-6100,2475)","0","mstr_standard","I56";
;
CDS_LIB"mstr_standard"
BODY_TYPE"PLUMBING"
HDL_TAP"TRUE";
"B \NAC \NWC"9;
"S \NAC"
BN"2"79;
%"TAP"
"1","(-6100,2575)","0","mstr_standard","I57";
;
CDS_LIB"mstr_standard"
BODY_TYPE"PLUMBING"
HDL_TAP"TRUE";
"B \NAC \NWC"9;
"S \NAC"
BN"4"81;
%"TAP"
"1","(-6100,2625)","0","mstr_standard","I58";
;
CDS_LIB"mstr_standard"
BODY_TYPE"PLUMBING"
HDL_TAP"TRUE";
"B \NAC \NWC"9;
"S \NAC"
BN"5"82;
%"TAP"
"1","(-6100,2675)","0","mstr_standard","I59";
;
CDS_LIB"mstr_standard"
BODY_TYPE"PLUMBING"
HDL_TAP"TRUE";
"B \NAC \NWC"9;
"S \NAC"
BN"6"83;
%"TAP"
"1","(-6100,2775)","0","mstr_standard","I60";
;
CDS_LIB"mstr_standard"
BODY_TYPE"PLUMBING"
HDL_TAP"TRUE";
"B \NAC \NWC"9;
"S \NAC"
BN"8"85;
%"TAP"
"1","(-6100,2725)","0","mstr_standard","I61";
;
CDS_LIB"mstr_standard"
BODY_TYPE"PLUMBING"
HDL_TAP"TRUE";
"B \NAC \NWC"9;
"S \NAC"
BN"7"84;
%"TAP"
"1","(-6100,2825)","0","mstr_standard","I62";
;
CDS_LIB"mstr_standard"
BODY_TYPE"PLUMBING"
HDL_TAP"TRUE";
"B \NAC \NWC"9;
"S \NAC"
BN"9"86;
%"TAP"
"1","(-6100,2875)","0","mstr_standard","I63";
;
CDS_LIB"mstr_standard"
BODY_TYPE"PLUMBING"
HDL_TAP"TRUE";
"B \NAC \NWC"9;
"S \NAC"
BN"10"87;
%"TAP"
"1","(-6100,2925)","0","mstr_standard","I64";
;
CDS_LIB"mstr_standard"
BODY_TYPE"PLUMBING"
HDL_TAP"TRUE";
"B \NAC \NWC"9;
"S \NAC"
BN"11"88;
%"TAP"
"1","(-6100,2975)","0","mstr_standard","I65";
;
CDS_LIB"mstr_standard"
BODY_TYPE"PLUMBING"
HDL_TAP"TRUE";
"B \NAC \NWC"9;
"S \NAC"
BN"12"89;
%"TAP"
"1","(-6100,3025)","0","mstr_standard","I66";
;
CDS_LIB"mstr_standard"
BODY_TYPE"PLUMBING"
HDL_TAP"TRUE";
"B \NAC \NWC"9;
"S \NAC"
BN"13"90;
%"TAP"
"1","(-6100,3125)","0","mstr_standard","I67";
;
CDS_LIB"mstr_standard"
BODY_TYPE"PLUMBING"
HDL_TAP"TRUE";
"B \NAC \NWC"9;
"S \NAC"
BN"15"92;
%"TAP"
"1","(-6100,3075)","0","mstr_standard","I68";
;
CDS_LIB"mstr_standard"
BODY_TYPE"PLUMBING"
HDL_TAP"TRUE";
"B \NAC \NWC"9;
"S \NAC"
BN"14"91;
%"TAP"
"1","(-6100,3175)","0","mstr_standard","I69";
;
CDS_LIB"mstr_standard"
BODY_TYPE"PLUMBING"
HDL_TAP"TRUE";
"B \NAC \NWC"9;
"S \NAC"
BN"16"24;
%"VCC_CORE"
"1","(-8650,3600)","0","mstr_symbols","I7";
;
HDL_POWER"P3V3_AUX"
ROOM"PVCCINFAON_CPU1_CTRL"
VOLTAGE"3.3"
CDS_LIB"mstr_symbols";
"A"16;
%"TAP"
"1","(-6100,3225)","0","mstr_standard","I70";
;
CDS_LIB"mstr_standard"
BODY_TYPE"PLUMBING"
HDL_TAP"TRUE";
"B \NAC \NWC"9;
"S \NAC"
BN"17"25;
%"TAP"
"1","(-6100,3275)","0","mstr_standard","I71";
;
CDS_LIB"mstr_standard"
BODY_TYPE"PLUMBING"
HDL_TAP"TRUE";
"B \NAC \NWC"9;
"S \NAC"
BN"18"93;
%"TAP"
"1","(-6100,3325)","0","mstr_standard","I72";
;
CDS_LIB"mstr_standard"
BODY_TYPE"PLUMBING"
HDL_TAP"TRUE";
"B \NAC \NWC"9;
"S \NAC"
BN"19"94;
%"TAP"
"1","(-6100,3425)","0","mstr_standard","I73";
;
CDS_LIB"mstr_standard"
BODY_TYPE"PLUMBING"
HDL_TAP"TRUE";
"B \NAC \NWC"9;
"S \NAC"
BN"21"96;
%"TAP"
"1","(-6100,3375)","0","mstr_standard","I74";
;
CDS_LIB"mstr_standard"
BODY_TYPE"PLUMBING"
HDL_TAP"TRUE";
"B \NAC \NWC"9;
"S \NAC"
BN"20"95;
%"TAP"
"1","(-6100,3475)","0","mstr_standard","I75";
;
CDS_LIB"mstr_standard"
BODY_TYPE"PLUMBING"
HDL_TAP"TRUE";
"B \NAC \NWC"9;
"S \NAC"
BN"22"97;
%"TAP"
"1","(-6100,3525)","0","mstr_standard","I76";
;
CDS_LIB"mstr_standard"
BODY_TYPE"PLUMBING"
HDL_TAP"TRUE";
"B \NAC \NWC"9;
"S \NAC"
BN"23"98;
%"TAP"
"1","(-6100,3575)","0","mstr_standard","I77";
;
CDS_LIB"mstr_standard"
BODY_TYPE"PLUMBING"
HDL_TAP"TRUE";
"B \NAC \NWC"9;
"S \NAC"
BN"24"99;
%"TAP"
"1","(-6100,3675)","0","mstr_standard","I78";
;
CDS_LIB"mstr_standard"
BODY_TYPE"PLUMBING"
HDL_TAP"TRUE";
"B \NAC \NWC"9;
"S \NAC"
BN"26"101;
%"TAP"
"1","(-6100,3625)","0","mstr_standard","I79";
;
CDS_LIB"mstr_standard"
BODY_TYPE"PLUMBING"
HDL_TAP"TRUE";
"B \NAC \NWC"9;
"S \NAC"
BN"25"100;
%"TAP"
"1","(-6100,3725)","0","mstr_standard","I80";
;
CDS_LIB"mstr_standard"
BODY_TYPE"PLUMBING"
HDL_TAP"TRUE";
"B \NAC \NWC"9;
"S \NAC"
BN"27"102;
%"TAP"
"1","(-6100,3775)","0","mstr_standard","I81";
;
CDS_LIB"mstr_standard"
BODY_TYPE"PLUMBING"
HDL_TAP"TRUE";
"B \NAC \NWC"9;
"S \NAC"
BN"28"103;
%"TAP"
"1","(-6100,3875)","0","mstr_standard","I82";
;
CDS_LIB"mstr_standard"
BODY_TYPE"PLUMBING"
HDL_TAP"TRUE";
"B \NAC \NWC"9;
"S \NAC"
BN"30"105;
%"TAP"
"1","(-6100,3825)","0","mstr_standard","I83";
;
CDS_LIB"mstr_standard"
BODY_TYPE"PLUMBING"
HDL_TAP"TRUE";
"B \NAC \NWC"9;
"S \NAC"
BN"29"104;
%"TAP"
"1","(-6100,3925)","0","mstr_standard","I84";
;
CDS_LIB"mstr_standard"
BODY_TYPE"PLUMBING"
HDL_TAP"TRUE";
"B \NAC \NWC"9;
"S \NAC"
BN"31"106;
%"TAP"
"1","(-6100,4025)","0","mstr_standard","I85";
;
CDS_LIB"mstr_standard"
BODY_TYPE"PLUMBING"
HDL_TAP"TRUE";
"B \NAC \NWC"8;
"S \NAC"
BN"0"107;
%"TAP"
"1","(-6100,4125)","0","mstr_standard","I86";
;
CDS_LIB"mstr_standard"
BODY_TYPE"PLUMBING"
HDL_TAP"TRUE";
"B \NAC \NWC"8;
"S \NAC"
BN"2"109;
%"TAP"
"1","(-6100,4075)","0","mstr_standard","I87";
;
CDS_LIB"mstr_standard"
BODY_TYPE"PLUMBING"
HDL_TAP"TRUE";
"B \NAC \NWC"8;
"S \NAC"
BN"1"108;
%"TAP"
"1","(-6100,4175)","0","mstr_standard","I88";
;
CDS_LIB"mstr_standard"
BODY_TYPE"PLUMBING"
HDL_TAP"TRUE";
"B \NAC \NWC"8;
"S \NAC"
BN"3"110;
END.
